(kicad_pcb
	(version 20260206)
	(generator "pcbnew")
	(generator_version "10.0")
	(general
		(thickness 1.6)
		(legacy_teardrops no)
	)
	(paper "A4")
	(title_block
		(title "baseboard — 13948-1b.1110WZS1818.brd")
		(comment 1 "Honey Badger (Wiwynn) / footprints 362-368 of 2523")
	)
	(layers
		(0 "F.Cu" signal "TOP")
		(4 "In1.Cu" signal "L2GND")
		(6 "In2.Cu" signal "L3")
		(8 "In3.Cu" signal "L4VCC")
		(10 "In4.Cu" signal "L5VCC")
		(12 "In5.Cu" signal "L6")
		(14 "In6.Cu" signal "L7GND")
		(2 "B.Cu" signal "BOTTOM")
		(9 "F.Adhes" user "F.Adhesive")
		(11 "B.Adhes" user "B.Adhesive")
		(13 "F.Paste" user "Package Geometry/Pastemask Top")
		(15 "B.Paste" user "Package Geometry/Pastemask Bottom")
		(5 "F.SilkS" user "Ref Des/Silkscreen Top")
		(7 "B.SilkS" user "Ref Des/Silkscreen Bottom")
		(1 "F.Mask" user "Board Geometry/Soldermask Top")
		(3 "B.Mask" user "Board Geometry/Soldermask Bottom")
		(17 "Dwgs.User" user "User.Drawings")
		(19 "Cmts.User" user "User.Comments")
		(21 "Eco1.User" user "User.Eco1")
		(23 "Eco2.User" user "User.Eco2")
		(25 "Edge.Cuts" user "Board Geometry/Outline")
		(27 "Margin" user)
		(31 "F.CrtYd" user "Package Geometry/Place Bound Top")
		(29 "B.CrtYd" user "Package Geometry/Place Bound Bottom")
		(35 "F.Fab" user "Ref Des/Assembly Top")
		(33 "B.Fab" user "Ref Des/Assembly Bottom")
	)
	(footprint ""
		(layer "F.Cu")
		(at 96.144842 -98.496882 -90)
		(property "Reference" "SR804"
			(at 0 0 270)
			(layer "F.SilkS")
			(hide yes)
			(effects
				(font
					(size 1.27 1.27)
				)
			)
		)
		(property "Value" "4K75R2F-1-GP"
			(at 0.064008 -3.993896 270)
			(unlocked yes)
			(layer "F.Fab")
			(hide yes)
			(effects
				(font
					(size 1.016 1.016)
					(thickness 0.1524)
				)
			)
		)
		(property "Device Type" "R402H16"
			(at 0.064008 -5.517896 270)
			(unlocked yes)
			(layer "F.Fab")
			(hide yes)
			(effects
				(font
					(size 1.016 1.016)
					(thickness 0.1524)
				)
			)
		)
		(duplicate_pad_numbers_are_jumpers no)
		(fp_line
			(start -0.508 -0.9398)
			(end -0.508 0.9398)
			(stroke
				(width 0.1524)
				(type default)
			)
			(layer "F.SilkS")
		)
		(fp_line
			(start 0.508 -0.9398)
			(end -0.508 -0.9398)
			(stroke
				(width 0.1524)
				(type default)
			)
			(layer "F.SilkS")
		)
		(fp_rect
			(start -0.508 0.9398)
			(end 0.508 -0.9398)
			(stroke
				(width 0)
				(type default)
			)
			(fill no)
			(layer "F.CrtYd")
		)
		(fp_rect
			(start -0.508 0.9398)
			(end 0.508 -0.9398)
			(stroke
				(width 0)
				(type default)
			)
			(fill no)
			(layer "F.Fab")
		)
		(pad "1" smd custom
			(at 0 -0.4445 270)
			(size 0.1397 0.1397)
			(layers "F.Cu" "F.Mask" "F.Paste")
			(net "LSI_EFUSE")
			(options
				(clearance outline)
				(anchor circle)
			)
			(primitives
				(gr_poly
					(pts
						(arc
							(start -0.1778 -0.2794)
							(mid -0.249642 -0.249642)
							(end -0.2794 -0.1778)
						)
						(arc
							(start -0.2794 0.1778)
							(mid -0.249642 0.249642)
							(end -0.1778 0.2794)
						)
						(arc
							(start 0.1778 0.2794)
							(mid 0.249642 0.249642)
							(end 0.2794 0.1778)
						)
						(arc
							(start 0.2794 -0.1778)
							(mid 0.249642 -0.249642)
							(end 0.1778 -0.2794)
						)
					)
					(width 0)
					(fill yes)
				)
			)
		)
		(pad "2" smd custom
			(at 0 0.4445 270)
			(size 0.1397 0.1397)
			(layers "F.Cu" "F.Mask" "F.Paste")
			(net "GND")
			(options
				(clearance outline)
				(anchor circle)
			)
			(primitives
				(gr_poly
					(pts
						(arc
							(start -0.1778 -0.2794)
							(mid -0.249642 -0.249642)
							(end -0.2794 -0.1778)
						)
						(arc
							(start -0.2794 0.1778)
							(mid -0.249642 0.249642)
							(end -0.1778 0.2794)
						)
						(arc
							(start 0.1778 0.2794)
							(mid 0.249642 0.249642)
							(end 0.2794 0.1778)
						)
						(arc
							(start 0.2794 -0.1778)
							(mid 0.249642 -0.249642)
							(end 0.1778 -0.2794)
						)
					)
					(width 0)
					(fill yes)
				)
			)
		)
	)
	(footprint ""
		(layer "F.Cu")
		(at 333.912718 -144.503648 90)
		(property "Reference" "R558"
			(at 0 0 90)
			(layer "F.SilkS")
			(hide yes)
			(effects
				(font
					(size 1.27 1.27)
				)
			)
		)
		(property "Value" "0R2J-2-GP"
			(at 0.064008 -3.993896 90)
			(unlocked yes)
			(layer "F.Fab")
			(hide yes)
			(effects
				(font
					(size 1.016 1.016)
					(thickness 0.1524)
				)
			)
		)
		(property "Device Type" "R402H16"
			(at 0.064008 -5.517896 90)
			(unlocked yes)
			(layer "F.Fab")
			(hide yes)
			(effects
				(font
					(size 1.016 1.016)
					(thickness 0.1524)
				)
			)
		)
		(duplicate_pad_numbers_are_jumpers no)
		(fp_line
			(start 0.508 -0.9398)
			(end -0.508 -0.9398)
			(stroke
				(width 0.1524)
				(type default)
			)
			(layer "F.SilkS")
		)
		(fp_line
			(start -0.508 -0.9398)
			(end -0.508 0.9398)
			(stroke
				(width 0.1524)
				(type default)
			)
			(layer "F.SilkS")
		)
		(fp_rect
			(start -0.508 0.9398)
			(end 0.508 -0.9398)
			(stroke
				(width 0)
				(type default)
			)
			(fill no)
			(layer "F.CrtYd")
		)
		(fp_rect
			(start -0.508 0.9398)
			(end 0.508 -0.9398)
			(stroke
				(width 0)
				(type default)
			)
			(fill no)
			(layer "F.Fab")
		)
		(pad "1" smd custom
			(at 0 -0.4445 90)
			(size 0.1397 0.1397)
			(layers "F.Cu" "F.Mask" "F.Paste")
			(net "PMU_PLTRST_N")
			(options
				(clearance outline)
				(anchor circle)
			)
			(primitives
				(gr_poly
					(pts
						(arc
							(start -0.1778 -0.2794)
							(mid -0.249642 -0.249642)
							(end -0.2794 -0.1778)
						)
						(arc
							(start -0.2794 0.1778)
							(mid -0.249642 0.249642)
							(end -0.1778 0.2794)
						)
						(arc
							(start 0.1778 0.2794)
							(mid 0.249642 0.249642)
							(end 0.2794 0.1778)
						)
						(arc
							(start 0.2794 -0.1778)
							(mid 0.249642 -0.249642)
							(end 0.1778 -0.2794)
						)
					)
					(width 0)
					(fill yes)
				)
			)
		)
		(pad "2" smd custom
			(at 0 0.4445 90)
			(size 0.1397 0.1397)
			(layers "F.Cu" "F.Mask" "F.Paste")
			(net "USB_RESET_N")
			(options
				(clearance outline)
				(anchor circle)
			)
			(primitives
				(gr_poly
					(pts
						(arc
							(start -0.1778 -0.2794)
							(mid -0.249642 -0.249642)
							(end -0.2794 -0.1778)
						)
						(arc
							(start -0.2794 0.1778)
							(mid -0.249642 0.249642)
							(end -0.1778 0.2794)
						)
						(arc
							(start 0.1778 0.2794)
							(mid 0.249642 0.249642)
							(end 0.2794 0.1778)
						)
						(arc
							(start 0.2794 -0.1778)
							(mid 0.249642 -0.249642)
							(end 0.1778 -0.2794)
						)
					)
					(width 0)
					(fill yes)
				)
			)
		)
	)
	(footprint ""
		(layer "F.Cu")
		(at 339.979 -116.332)
		(property "Reference" "PR13"
			(at 0 0 0)
			(layer "F.SilkS")
			(hide yes)
			(effects
				(font
					(size 1.27 1.27)
				)
			)
		)
		(property "Value" "10KR2F-2-GP"
			(at 0.064008 -3.993896 0)
			(unlocked yes)
			(layer "F.Fab")
			(hide yes)
			(effects
				(font
					(size 1.016 1.016)
					(thickness 0.1524)
				)
			)
		)
		(property "Device Type" "R402H16"
			(at 0.064008 -5.517896 0)
			(unlocked yes)
			(layer "F.Fab")
			(hide yes)
			(effects
				(font
					(size 1.016 1.016)
					(thickness 0.1524)
				)
			)
		)
		(duplicate_pad_numbers_are_jumpers no)
		(fp_line
			(start -0.508 -0.9398)
			(end -0.508 0.9398)
			(stroke
				(width 0.1524)
				(type default)
			)
			(layer "F.SilkS")
		)
		(fp_line
			(start 0.508 -0.9398)
			(end -0.508 -0.9398)
			(stroke
				(width 0.1524)
				(type default)
			)
			(layer "F.SilkS")
		)
		(fp_rect
			(start -0.508 0.9398)
			(end 0.508 -0.9398)
			(stroke
				(width 0)
				(type default)
			)
			(fill no)
			(layer "F.CrtYd")
		)
		(fp_rect
			(start -0.508 0.9398)
			(end 0.508 -0.9398)
			(stroke
				(width 0)
				(type default)
			)
			(fill no)
			(layer "F.Fab")
		)
		(pad "1" smd custom
			(at 0 -0.4445)
			(size 0.1397 0.1397)
			(layers "F.Cu" "F.Mask" "F.Paste")
			(net "P5V_STBY_PG")
			(options
				(clearance outline)
				(anchor circle)
			)
			(primitives
				(gr_poly
					(pts
						(arc
							(start -0.1778 -0.2794)
							(mid -0.249642 -0.249642)
							(end -0.2794 -0.1778)
						)
						(arc
							(start -0.2794 0.1778)
							(mid -0.249642 0.249642)
							(end -0.1778 0.2794)
						)
						(arc
							(start 0.1778 0.2794)
							(mid 0.249642 0.249642)
							(end 0.2794 0.1778)
						)
						(arc
							(start 0.2794 -0.1778)
							(mid 0.249642 -0.249642)
							(end 0.1778 -0.2794)
						)
					)
					(width 0)
					(fill yes)
				)
			)
		)
		(pad "2" smd custom
			(at 0 0.4445)
			(size 0.1397 0.1397)
			(layers "F.Cu" "F.Mask" "F.Paste")
			(net "P5V_STBY_VRG5")
			(options
				(clearance outline)
				(anchor circle)
			)
			(primitives
				(gr_poly
					(pts
						(arc
							(start -0.1778 -0.2794)
							(mid -0.249642 -0.249642)
							(end -0.2794 -0.1778)
						)
						(arc
							(start -0.2794 0.1778)
							(mid -0.249642 0.249642)
							(end -0.1778 0.2794)
						)
						(arc
							(start 0.1778 0.2794)
							(mid 0.249642 0.249642)
							(end 0.2794 0.1778)
						)
						(arc
							(start 0.2794 -0.1778)
							(mid 0.249642 -0.249642)
							(end 0.1778 -0.2794)
						)
					)
					(width 0)
					(fill yes)
				)
			)
		)
	)
	(footprint ""
		(layer "F.Cu")
		(at 333.883 -80.772 90)
		(property "Reference" "R682"
			(at 0 0 90)
			(layer "F.SilkS")
			(hide yes)
			(effects
				(font
					(size 1.27 1.27)
				)
			)
		)
		(property "Value" "0R2J-2-GP"
			(at 0.064008 -3.993896 90)
			(unlocked yes)
			(layer "F.Fab")
			(hide yes)
			(effects
				(font
					(size 1.016 1.016)
					(thickness 0.1524)
				)
			)
		)
		(property "Device Type" "R402H16"
			(at 0.064008 -5.517896 90)
			(unlocked yes)
			(layer "F.Fab")
			(hide yes)
			(effects
				(font
					(size 1.016 1.016)
					(thickness 0.1524)
				)
			)
		)
		(duplicate_pad_numbers_are_jumpers no)
		(fp_line
			(start 0.508 -0.9398)
			(end -0.508 -0.9398)
			(stroke
				(width 0.1524)
				(type default)
			)
			(layer "F.SilkS")
		)
		(fp_line
			(start -0.508 -0.9398)
			(end -0.508 0.9398)
			(stroke
				(width 0.1524)
				(type default)
			)
			(layer "F.SilkS")
		)
		(fp_rect
			(start -0.508 0.9398)
			(end 0.508 -0.9398)
			(stroke
				(width 0)
				(type default)
			)
			(fill no)
			(layer "F.CrtYd")
		)
		(fp_rect
			(start -0.508 0.9398)
			(end 0.508 -0.9398)
			(stroke
				(width 0)
				(type default)
			)
			(fill no)
			(layer "F.Fab")
		)
		(pad "1" smd custom
			(at 0 -0.4445 90)
			(size 0.1397 0.1397)
			(layers "F.Cu" "F.Mask" "F.Paste")
			(net "ROMD2_R_R")
			(options
				(clearance outline)
				(anchor circle)
			)
			(primitives
				(gr_poly
					(pts
						(arc
							(start -0.1778 -0.2794)
							(mid -0.249642 -0.249642)
							(end -0.2794 -0.1778)
						)
						(arc
							(start -0.2794 0.1778)
							(mid -0.249642 0.249642)
							(end -0.1778 0.2794)
						)
						(arc
							(start 0.1778 0.2794)
							(mid 0.249642 0.249642)
							(end 0.2794 0.1778)
						)
						(arc
							(start 0.2794 -0.1778)
							(mid 0.249642 -0.249642)
							(end 0.1778 -0.2794)
						)
					)
					(width 0)
					(fill yes)
				)
			)
		)
		(pad "2" smd custom
			(at 0 0.4445 90)
			(size 0.1397 0.1397)
			(layers "F.Cu" "F.Mask" "F.Paste")
			(net "ROMD2_R")
			(options
				(clearance outline)
				(anchor circle)
			)
			(primitives
				(gr_poly
					(pts
						(arc
							(start -0.1778 -0.2794)
							(mid -0.249642 -0.249642)
							(end -0.2794 -0.1778)
						)
						(arc
							(start -0.2794 0.1778)
							(mid -0.249642 0.249642)
							(end -0.1778 0.2794)
						)
						(arc
							(start 0.1778 0.2794)
							(mid 0.249642 0.249642)
							(end 0.2794 0.1778)
						)
						(arc
							(start 0.2794 -0.1778)
							(mid 0.249642 -0.249642)
							(end 0.1778 -0.2794)
						)
					)
					(width 0)
					(fill yes)
				)
			)
		)
	)
	(footprint ""
		(layer "F.Cu")
		(at 343.408 -20.32)
		(property "Reference" "R453"
			(at 0 0 0)
			(layer "F.SilkS")
			(hide yes)
			(effects
				(font
					(size 1.27 1.27)
				)
			)
		)
		(property "Value" "8K2R2J-3-GP"
			(at 0.064008 -3.993896 0)
			(unlocked yes)
			(layer "F.Fab")
			(hide yes)
			(effects
				(font
					(size 1.016 1.016)
					(thickness 0.1524)
				)
			)
		)
		(property "Device Type" "R402H16"
			(at 0.064008 -5.517896 0)
			(unlocked yes)
			(layer "F.Fab")
			(hide yes)
			(effects
				(font
					(size 1.016 1.016)
					(thickness 0.1524)
				)
			)
		)
		(duplicate_pad_numbers_are_jumpers no)
		(fp_line
			(start -0.508 -0.9398)
			(end -0.508 0.9398)
			(stroke
				(width 0.1524)
				(type default)
			)
			(layer "F.SilkS")
		)
		(fp_line
			(start 0.508 -0.9398)
			(end -0.508 -0.9398)
			(stroke
				(width 0.1524)
				(type default)
			)
			(layer "F.SilkS")
		)
		(fp_rect
			(start -0.508 0.9398)
			(end 0.508 -0.9398)
			(stroke
				(width 0)
				(type default)
			)
			(fill no)
			(layer "F.CrtYd")
		)
		(fp_rect
			(start -0.508 0.9398)
			(end 0.508 -0.9398)
			(stroke
				(width 0)
				(type default)
			)
			(fill no)
			(layer "F.Fab")
		)
		(pad "1" smd custom
			(at 0 -0.4445)
			(size 0.1397 0.1397)
			(layers "F.Cu" "F.Mask" "F.Paste")
			(net "P3V3_STBY")
			(options
				(clearance outline)
				(anchor circle)
			)
			(primitives
				(gr_poly
					(pts
						(arc
							(start -0.1778 -0.2794)
							(mid -0.249642 -0.249642)
							(end -0.2794 -0.1778)
						)
						(arc
							(start -0.2794 0.1778)
							(mid -0.249642 0.249642)
							(end -0.1778 0.2794)
						)
						(arc
							(start 0.1778 0.2794)
							(mid 0.249642 0.249642)
							(end 0.2794 0.1778)
						)
						(arc
							(start 0.2794 -0.1778)
							(mid 0.249642 -0.249642)
							(end 0.1778 -0.2794)
						)
					)
					(width 0)
					(fill yes)
				)
			)
		)
		(pad "2" smd custom
			(at 0 0.4445)
			(size 0.1397 0.1397)
			(layers "F.Cu" "F.Mask" "F.Paste")
			(net "CPU_EXP_RST")
			(options
				(clearance outline)
				(anchor circle)
			)
			(primitives
				(gr_poly
					(pts
						(arc
							(start -0.1778 -0.2794)
							(mid -0.249642 -0.249642)
							(end -0.2794 -0.1778)
						)
						(arc
							(start -0.2794 0.1778)
							(mid -0.249642 0.249642)
							(end -0.1778 0.2794)
						)
						(arc
							(start 0.1778 0.2794)
							(mid 0.249642 0.249642)
							(end 0.2794 0.1778)
						)
						(arc
							(start 0.2794 -0.1778)
							(mid 0.249642 -0.249642)
							(end 0.1778 -0.2794)
						)
					)
					(width 0)
					(fill yes)
				)
			)
		)
	)
	(footprint ""
		(layer "F.Cu")
		(at 85.857842 -116.530882 90)
		(property "Reference" "SU66"
			(at 0 0 90)
			(layer "F.SilkS")
			(hide yes)
			(effects
				(font
					(size 1.27 1.27)
				)
			)
		)
		(property "Value" "PCA9306DCTT-GP"
			(at 0 -11.6332 90)
			(unlocked yes)
			(layer "F.Fab")
			(hide yes)
			(effects
				(font
					(size 1.016 1.016)
					(thickness 0.1524)
				)
			)
		)
		(property "Device Type" "SSOIC8H52"
			(at 0 -13.1572 90)
			(unlocked yes)
			(layer "F.Fab")
			(hide yes)
			(effects
				(font
					(size 1.016 1.016)
					(thickness 0.1524)
				)
			)
		)
		(duplicate_pad_numbers_are_jumpers no)
		(fp_line
			(start 1.0668 -0.5842)
			(end 1.0668 0.5842)
			(stroke
				(width 0.1524)
				(type default)
			)
			(layer "F.SilkS")
		)
		(fp_line
			(start -1.7018 -0.5842)
			(end 1.0668 -0.5842)
			(stroke
				(width 0.1524)
				(type default)
			)
			(layer "F.SilkS")
		)
		(fp_line
			(start -1.7018 -0.5842)
			(end -1.7018 2.286)
			(stroke
				(width 0.1524)
				(type default)
			)
			(layer "F.SilkS")
		)
		(fp_line
			(start -1.397 0)
			(end -1.7018 -0.3048)
			(stroke
				(width 0.1524)
				(type default)
			)
			(layer "F.SilkS")
		)
		(fp_line
			(start -1.397 0)
			(end -1.7018 0.3048)
			(stroke
				(width 0.1524)
				(type default)
			)
			(layer "F.SilkS")
		)
		(fp_line
			(start 1.0668 0.5842)
			(end -1.524 0.5842)
			(stroke
				(width 0.1524)
				(type default)
			)
			(layer "F.SilkS")
		)
		(fp_line
			(start -1.524 0.5842)
			(end -1.524 2.286)
			(stroke
				(width 0.508)
				(type default)
			)
			(layer "F.SilkS")
		)
		(fp_poly
			(pts
				(xy -1.1684 -0.5842) (xy 1.0668 -0.5842) (xy 1.0668 0.5842) (xy -1.1684 0.5842)
			)
			(stroke
				(width 0)
				(type default)
			)
			(fill yes)
			(layer "F.SilkS")
		)
		(fp_poly
			(pts
				(xy -1.778 2.54) (xy 1.778 2.54) (xy 1.778 -2.54) (xy -1.778 -2.54)
			)
			(stroke
				(width 0)
				(type default)
			)
			(fill no)
			(layer "F.CrtYd")
		)
		(fp_poly
			(pts
				(xy -1.778 -2.54) (xy 1.778 -2.54) (xy 1.778 2.54) (xy -1.778 2.54)
			)
			(stroke
				(width 0)
				(type default)
			)
			(fill no)
			(layer "F.Fab")
		)
		(pad "1" smd rect
			(at -0.97536 1.6256 90)
			(size 0.3556 1.524)
			(layers "F.Cu" "F.Mask" "F.Paste")
			(net "GND")
		)
		(pad "2" smd rect
			(at -0.32512 1.6256 90)
			(size 0.3556 1.524)
			(layers "F.Cu" "F.Mask" "F.Paste")
			(net "P1V8_E")
		)
		(pad "3" smd rect
			(at 0.32512 1.6256 90)
			(size 0.3556 1.524)
			(layers "F.Cu" "F.Mask" "F.Paste")
			(net "EXP_I2C_SCL_2")
		)
		(pad "4" smd rect
			(at 0.97536 1.6256 90)
			(size 0.3556 1.524)
			(layers "F.Cu" "F.Mask" "F.Paste")
			(net "EXP_I2C_SDA_2")
		)
		(pad "5" smd rect
			(at 0.97536 -1.6256 90)
			(size 0.3556 1.524)
			(layers "F.Cu" "F.Mask" "F.Paste")
			(net "EXP_IOC_BMC_SDA_14")
		)
		(pad "6" smd rect
			(at 0.32512 -1.6256 90)
			(size 0.3556 1.524)
			(layers "F.Cu" "F.Mask" "F.Paste")
			(net "EXP_IOC_BMC_SCL_14")
		)
		(pad "7" smd rect
			(at -0.32512 -1.6256 90)
			(size 0.3556 1.524)
			(layers "F.Cu" "F.Mask" "F.Paste")
			(net "EXP_I2C_VREF_1")
		)
		(pad "8" smd rect
			(at -0.97536 -1.6256 90)
			(size 0.3556 1.524)
			(layers "F.Cu" "F.Mask" "F.Paste")
			(net "EXP_I2C_VREF_1")
		)
	)
	(footprint ""
		(layer "F.Cu")
		(at 270.374872 -57.730136 -90)
		(property "Reference" "PR114"
			(at 0 0 270)
			(layer "F.SilkS")
			(hide yes)
			(effects
				(font
					(size 1.27 1.27)
				)
			)
		)
		(property "Value" "4K02R2F-GP"
			(at 0.064008 -3.993896 270)
			(unlocked yes)
			(layer "F.Fab")
			(hide yes)
			(effects
				(font
					(size 1.016 1.016)
					(thickness 0.1524)
				)
			)
		)
		(property "Device Type" "R402H16"
			(at 0.064008 -5.517896 270)
			(unlocked yes)
			(layer "F.Fab")
			(hide yes)
			(effects
				(font
					(size 1.016 1.016)
					(thickness 0.1524)
				)
			)
		)
		(duplicate_pad_numbers_are_jumpers no)
		(fp_line
			(start -0.508 -0.9398)
			(end -0.508 0.9398)
			(stroke
				(width 0.1524)
				(type default)
			)
			(layer "F.SilkS")
		)
		(fp_line
			(start 0.508 -0.9398)
			(end -0.508 -0.9398)
			(stroke
				(width 0.1524)
				(type default)
			)
			(layer "F.SilkS")
		)
		(fp_rect
			(start -0.508 0.9398)
			(end 0.508 -0.9398)
			(stroke
				(width 0)
				(type default)
			)
			(fill no)
			(layer "F.CrtYd")
		)
		(fp_rect
			(start -0.508 0.9398)
			(end 0.508 -0.9398)
			(stroke
				(width 0)
				(type default)
			)
			(fill no)
			(layer "F.Fab")
		)
		(pad "1" smd custom
			(at 0 -0.4445 270)
			(size 0.1397 0.1397)
			(layers "F.Cu" "F.Mask" "F.Paste")
			(net "P3V3_EN_G")
			(options
				(clearance outline)
				(anchor circle)
			)
			(primitives
				(gr_poly
					(pts
						(arc
							(start -0.1778 -0.2794)
							(mid -0.249642 -0.249642)
							(end -0.2794 -0.1778)
						)
						(arc
							(start -0.2794 0.1778)
							(mid -0.249642 0.249642)
							(end -0.1778 0.2794)
						)
						(arc
							(start 0.1778 0.2794)
							(mid 0.249642 0.249642)
							(end 0.2794 0.1778)
						)
						(arc
							(start 0.2794 -0.1778)
							(mid 0.249642 -0.249642)
							(end 0.1778 -0.2794)
						)
					)
					(width 0)
					(fill yes)
				)
			)
		)
		(pad "2" smd custom
			(at 0 0.4445 270)
			(size 0.1397 0.1397)
			(layers "F.Cu" "F.Mask" "F.Paste")
			(net "P3V3_STBY")
			(options
				(clearance outline)
				(anchor circle)
			)
			(primitives
				(gr_poly
					(pts
						(arc
							(start -0.1778 -0.2794)
							(mid -0.249642 -0.249642)
							(end -0.2794 -0.1778)
						)
						(arc
							(start -0.2794 0.1778)
							(mid -0.249642 0.249642)
							(end -0.1778 0.2794)
						)
						(arc
							(start 0.1778 0.2794)
							(mid 0.249642 0.249642)
							(end 0.2794 0.1778)
						)
						(arc
							(start 0.2794 -0.1778)
							(mid 0.249642 -0.249642)
							(end 0.1778 -0.2794)
						)
					)
					(width 0)
					(fill yes)
				)
			)
		)
	)
)
